# SCM (Grand Teton) — schematic netlist excerpt (pin names and nets, part order shuffled) for the footprints in the layout excerpt that follows; sources: Cadence DE-HDL packaged netlist, KiCad conversion of 12092022_DA0F0TMDCD0_F0T_Management_Board_D_brd_V3_OCP.brd

C146  Q_CAP  0.1UF 25V 10% X7R  pkg 0402  page 44 : A = P3V3_AUX ; B = GND
C64  Q_CAP  1UF 25V 10% X6S  pkg C0402  page 16 : A = P1V0_STBY_PLAVDD ; B = GND

(kicad_pcb
	(version 20260206)
	(generator "pcbnew")
	(generator_version "10.0")
	(general
		(thickness 1.6)
		(legacy_teardrops no)
	)
	(paper "A4")
	(title_block
		(title "12092022_DA0F0TMDCD0_F0T_Management_Board_D_brd_V3_OCP.brd")
		(comment 1 "Grand Teton / footprints 783-784 of 1440")
	)
	(layers
		(0 "F.Cu" signal "TOP")
		(4 "In1.Cu" signal "GND")
		(6 "In2.Cu" signal "IN1")
		(8 "In3.Cu" signal "GND1")
		(10 "In4.Cu" signal "IN2")
		(12 "In5.Cu" signal "VCC")
		(14 "In6.Cu" signal "VCC1")
		(16 "In7.Cu" signal "IN3")
		(18 "In8.Cu" signal "GND2")
		(20 "In9.Cu" signal "IN4")
		(22 "In10.Cu" signal "GND3")
		(2 "B.Cu" signal "BOTTOM")
		(9 "F.Adhes" user "F.Adhesive")
		(11 "B.Adhes" user "B.Adhesive")
		(13 "F.Paste" user "Package Geometry/Pastemask Top")
		(15 "B.Paste" user "Package Geometry/Pastemask Bottom")
		(5 "F.SilkS" user "Ref Des/Silkscreen Top")
		(7 "B.SilkS" user "Ref Des/Silkscreen Bottom")
		(1 "F.Mask" user "Board Geometry/Soldermask Top")
		(3 "B.Mask" user "Board Geometry/Soldermask Bottom")
		(17 "Dwgs.User" user "User.Drawings")
		(19 "Cmts.User" user "User.Comments")
		(21 "Eco1.User" user "User.Eco1")
		(23 "Eco2.User" user "User.Eco2")
		(25 "Edge.Cuts" user "Board Geometry/Outline")
		(27 "Margin" user)
		(31 "F.CrtYd" user "Package Geometry/Place Bound Top")
		(29 "B.CrtYd" user "Package Geometry/Place Bound Bottom")
		(35 "F.Fab" user "Ref Des/Assembly Top")
		(33 "B.Fab" user "Ref Des/Assembly Bottom")
	)
	(footprint ""
		(layer "B.Cu")
		(at 37.4015 -103.632)
		(property "Reference" "C146"
			(at 0 0 0)
			(layer "B.SilkS")
			(hide yes)
			(effects
				(font
					(size 1.27 1.27)
				)
				(justify mirror)
			)
		)
		(property "Value" ""
			(at 0 0 0)
			(layer "B.Fab")
			(effects
				(font
					(size 1.27 1.27)
				)
				(justify mirror)
			)
		)
		(duplicate_pad_numbers_are_jumpers no)
		(fp_line
			(start -0.7874 -0.4064)
			(end -0.7874 0.4064)
			(stroke
				(width 0.1524)
				(type default)
			)
			(layer "B.SilkS")
		)
		(fp_line
			(start -0.7874 0.4064)
			(end 0.7874 0.4064)
			(stroke
				(width 0.1524)
				(type default)
			)
			(layer "B.SilkS")
		)
		(fp_line
			(start 0.7874 -0.4064)
			(end -0.7874 -0.4064)
			(stroke
				(width 0.1524)
				(type default)
			)
			(layer "B.SilkS")
		)
		(fp_line
			(start 0.7874 0.4064)
			(end 0.7874 -0.4064)
			(stroke
				(width 0.1524)
				(type default)
			)
			(layer "B.SilkS")
		)
		(fp_line
			(start -0.67945 -0.3048)
			(end -0.67945 0.3048)
			(stroke
				(width 0.1)
				(type default)
			)
			(layer "B.Fab")
		)
		(fp_line
			(start -0.67945 0.3048)
			(end -0.120396 0.3048)
			(stroke
				(width 0.1)
				(type default)
			)
			(layer "B.Fab")
		)
		(fp_line
			(start -0.12065 -0.3048)
			(end -0.67945 -0.3048)
			(stroke
				(width 0.1)
				(type default)
			)
			(layer "B.Fab")
		)
		(fp_line
			(start -0.12065 -0.2794)
			(end -0.12065 -0.3048)
			(stroke
				(width 0.1)
				(type default)
			)
			(layer "B.Fab")
		)
		(fp_line
			(start -0.120396 0.2794)
			(end 0.12065 0.2794)
			(stroke
				(width 0.1)
				(type default)
			)
			(layer "B.Fab")
		)
		(fp_line
			(start -0.120396 0.3048)
			(end -0.120396 0.2794)
			(stroke
				(width 0.1)
				(type default)
			)
			(layer "B.Fab")
		)
		(fp_line
			(start 0.12065 -0.305054)
			(end 0.12065 -0.2794)
			(stroke
				(width 0.1)
				(type default)
			)
			(layer "B.Fab")
		)
		(fp_line
			(start 0.12065 -0.2794)
			(end -0.12065 -0.2794)
			(stroke
				(width 0.1)
				(type default)
			)
			(layer "B.Fab")
		)
		(fp_line
			(start 0.12065 0.2794)
			(end 0.12065 0.3048)
			(stroke
				(width 0.1)
				(type default)
			)
			(layer "B.Fab")
		)
		(fp_line
			(start 0.12065 0.3048)
			(end 0.67945 0.3048)
			(stroke
				(width 0.1)
				(type default)
			)
			(layer "B.Fab")
		)
		(fp_line
			(start 0.67945 -0.305054)
			(end 0.12065 -0.305054)
			(stroke
				(width 0.1)
				(type default)
			)
			(layer "B.Fab")
		)
		(fp_line
			(start 0.67945 0.3048)
			(end 0.67945 -0.305054)
			(stroke
				(width 0.1)
				(type default)
			)
			(layer "B.Fab")
		)
		(pad "1" smd circle
			(at 0.40005 0 180)
			(size 0 0)
			(layers "B.Cu" "B.Mask" "B.Paste")
			(net "P3V3_AUX")
		)
		(pad "2" smd circle
			(at -0.40005 0 180)
			(size 0 0)
			(layers "B.Cu" "B.Mask" "B.Paste")
			(net "GND")
		)
	)
	(footprint ""
		(layer "B.Cu")
		(at 57.673494 -44.412662 -90)
		(property "Reference" "C64"
			(at 0 0 90)
			(layer "B.SilkS")
			(hide yes)
			(effects
				(font
					(size 1.27 1.27)
				)
				(justify mirror)
			)
		)
		(property "Value" ""
			(at 0 0 90)
			(layer "B.Fab")
			(effects
				(font
					(size 1.27 1.27)
				)
				(justify mirror)
			)
		)
		(duplicate_pad_numbers_are_jumpers no)
		(fp_line
			(start -0.7874 0.4064)
			(end 0.7874 0.4064)
			(stroke
				(width 0.1524)
				(type default)
			)
			(layer "B.SilkS")
		)
		(fp_line
			(start 0.7874 0.4064)
			(end 0.7874 -0.4064)
			(stroke
				(width 0.1524)
				(type default)
			)
			(layer "B.SilkS")
		)
		(fp_line
			(start -0.7874 -0.4064)
			(end -0.7874 0.4064)
			(stroke
				(width 0.1524)
				(type default)
			)
			(layer "B.SilkS")
		)
		(fp_line
			(start 0.7874 -0.4064)
			(end -0.7874 -0.4064)
			(stroke
				(width 0.1524)
				(type default)
			)
			(layer "B.SilkS")
		)
		(fp_line
			(start -0.67945 0.3048)
			(end -0.120396 0.3048)
			(stroke
				(width 0.1)
				(type default)
			)
			(layer "B.Fab")
		)
		(fp_line
			(start -0.120396 0.3048)
			(end -0.120396 0.2794)
			(stroke
				(width 0.1)
				(type default)
			)
			(layer "B.Fab")
		)
		(fp_line
			(start 0.12065 0.3048)
			(end 0.67945 0.3048)
			(stroke
				(width 0.1)
				(type default)
			)
			(layer "B.Fab")
		)
		(fp_line
			(start 0.67945 0.3048)
			(end 0.67945 -0.305054)
			(stroke
				(width 0.1)
				(type default)
			)
			(layer "B.Fab")
		)
		(fp_line
			(start -0.120396 0.2794)
			(end 0.12065 0.2794)
			(stroke
				(width 0.1)
				(type default)
			)
			(layer "B.Fab")
		)
		(fp_line
			(start 0.12065 0.2794)
			(end 0.12065 0.3048)
			(stroke
				(width 0.1)
				(type default)
			)
			(layer "B.Fab")
		)
		(fp_line
			(start -0.12065 -0.2794)
			(end -0.12065 -0.3048)
			(stroke
				(width 0.1)
				(type default)
			)
			(layer "B.Fab")
		)
		(fp_line
			(start 0.12065 -0.2794)
			(end -0.12065 -0.2794)
			(stroke
				(width 0.1)
				(type default)
			)
			(layer "B.Fab")
		)
		(fp_line
			(start -0.67945 -0.3048)
			(end -0.67945 0.3048)
			(stroke
				(width 0.1)
				(type default)
			)
			(layer "B.Fab")
		)
		(fp_line
			(start -0.12065 -0.3048)
			(end -0.67945 -0.3048)
			(stroke
				(width 0.1)
				(type default)
			)
			(layer "B.Fab")
		)
		(fp_line
			(start 0.12065 -0.305054)
			(end 0.12065 -0.2794)
			(stroke
				(width 0.1)
				(type default)
			)
			(layer "B.Fab")
		)
		(fp_line
			(start 0.67945 -0.305054)
			(end 0.12065 -0.305054)
			(stroke
				(width 0.1)
				(type default)
			)
			(layer "B.Fab")
		)
		(pad "1" smd circle
			(at 0.40005 0 90)
			(size 0 0)
			(layers "B.Cu" "B.Mask" "B.Paste")
			(net "P1V0_STBY_PLAVDD")
		)
		(pad "2" smd circle
			(at -0.40005 0 90)
			(size 0 0)
			(layers "B.Cu" "B.Mask" "B.Paste")
			(net "GND")
		)
	)
)
